(kicad_pcb
	(version 20241229)
	(generator "pcbnew")
	(generator_version "9.0")
	(general
		(thickness 1.62)
		(legacy_teardrops no)
	)
	(paper "A3")
	(title_block
		(title "COM Express 7 Baseboard")
		(date "2025-02-04")
		(rev "1.1.2")
		(company "Antmicro Ltd")
		(comment 1 "www.antmicro.com")
		(comment 9 "footprints 116-118 of 802")
	)
	(layers
		(0 "F.Cu" signal)
		(4 "In1.Cu" signal)
		(6 "In2.Cu" signal)
		(8 "In3.Cu" signal)
		(10 "In4.Cu" signal)
		(12 "In5.Cu" signal)
		(14 "In6.Cu" signal)
		(2 "B.Cu" signal)
		(9 "F.Adhes" user "F.Adhesive")
		(11 "B.Adhes" user "B.Adhesive")
		(13 "F.Paste" user)
		(15 "B.Paste" user)
		(5 "F.SilkS" user "F.Silkscreen")
		(7 "B.SilkS" user "B.Silkscreen")
		(1 "F.Mask" user)
		(3 "B.Mask" user)
		(17 "Dwgs.User" user "User.Drawings")
		(19 "Cmts.User" user "User.Comments")
		(21 "Eco1.User" user "User.Eco1")
		(23 "Eco2.User" user "User.Eco2")
		(25 "Edge.Cuts" user)
		(27 "Margin" user)
		(31 "F.CrtYd" user "F.Courtyard")
		(29 "B.CrtYd" user "B.Courtyard")
		(35 "F.Fab" user)
		(33 "B.Fab" user)
	)
	(footprint "antmicro-footprints:R_0201"
		(layer "F.Cu")
		(at 132.17 147.961 -90)
		(descr "Resistor SMD 0201")
		(tags "resistor SMD 0201")
		(property "Reference" "R310"
			(at 3.6 -0.58 90)
			(layer "F.SilkS")
			(effects
				(font
					(size 0.7 0.7)
					(thickness 0.15)
				)
				(justify right bottom)
			)
		)
		(property "Value" "R_0R_0201"
			(at 0 1.25 90)
			(layer "F.Fab")
			(effects
				(font
					(size 0.7 0.7)
					(thickness 0.15)
				)
				(justify right bottom)
			)
		)
		(property "Datasheet" "https://www.bourns.com/docs/product-datasheets/cr.pdf"
			(at 0 0 270)
			(layer "F.Fab")
			(hide yes)
			(effects
				(font
					(size 1.27 1.27)
					(thickness 0.15)
				)
			)
		)
		(property "Author" "Antmicro"
			(at -15.791 280.131 0)
			(layer "F.Fab")
			(hide yes)
			(effects
				(font
					(size 1 1)
					(thickness 0.15)
				)
			)
		)
		(property "License" "Apache-2.0"
			(at -15.791 280.131 0)
			(layer "F.Fab")
			(hide yes)
			(effects
				(font
					(size 1 1)
					(thickness 0.15)
				)
			)
		)
		(property "MPN" "CR0201-FX-0R00GLF"
			(at -15.791 280.131 0)
			(layer "F.Fab")
			(hide yes)
			(effects
				(font
					(size 1 1)
					(thickness 0.15)
				)
			)
		)
		(property "Manufacturer" "Bourns"
			(at -15.791 280.131 0)
			(layer "F.Fab")
			(hide yes)
			(effects
				(font
					(size 1 1)
					(thickness 0.15)
				)
			)
		)
		(property "Tolerance" "1%"
			(at -15.791 280.131 0)
			(layer "F.Fab")
			(hide yes)
			(effects
				(font
					(size 1 1)
					(thickness 0.15)
				)
			)
		)
		(property "Val" "0R"
			(at -15.791 280.131 0)
			(layer "F.Fab")
			(hide yes)
			(effects
				(font
					(size 1 1)
					(thickness 0.15)
				)
			)
		)
		(sheetname "KR to SFI #2")
		(sheetfile "kr_sfi.kicad_sch")
		(attr smd dnp)
		(fp_rect
			(start -0.7 -0.35)
			(end 0.7 0.35)
			(stroke
				(width 0.05)
				(type default)
			)
			(fill no)
			(layer "F.CrtYd")
		)
		(fp_rect
			(start -0.3 -0.15)
			(end 0.298 0.148)
			(stroke
				(width 0.15)
				(type solid)
			)
			(fill no)
			(layer "F.Fab")
		)
		(pad "" smd roundrect
			(at -0.346 0 270)
			(size 0.318 0.36)
			(layers "F.Paste")
			(roundrect_rratio 0.25)
			(teardrops
				(best_length_ratio 0.2)
				(max_length 1)
				(best_width_ratio 0.9)
				(max_width 2)
				(curved_edges yes)
				(filter_ratio 0.9)
				(enabled yes)
				(allow_two_segments yes)
				(prefer_zone_connections yes)
			)
		)
		(pad "" smd roundrect
			(at 0.344 0 270)
			(size 0.318 0.36)
			(layers "F.Paste")
			(roundrect_rratio 0.25)
			(teardrops
				(best_length_ratio 0.2)
				(max_length 1)
				(best_width_ratio 0.9)
				(max_width 2)
				(curved_edges yes)
				(filter_ratio 0.9)
				(enabled yes)
				(allow_two_segments yes)
				(prefer_zone_connections yes)
			)
		)
		(pad "1" smd roundrect
			(at -0.32 0 270)
			(size 0.46 0.4)
			(layers "F.Cu" "F.Mask")
			(roundrect_rratio 0.25)
			(net 877 "/2xSFP+/SFI1.RX-")
			(pintype "passive")
			(teardrops
				(best_length_ratio 0.2)
				(max_length 1)
				(best_width_ratio 0.9)
				(max_width 2)
				(curved_edges yes)
				(filter_ratio 0.9)
				(enabled yes)
				(allow_two_segments yes)
				(prefer_zone_connections yes)
			)
		)
		(pad "2" smd roundrect
			(at 0.32 0 270)
			(size 0.46 0.4)
			(layers "F.Cu" "F.Mask")
			(roundrect_rratio 0.25)
			(net 968 "/2xSFP+/KR to SFI #2/BYP_RX-")
			(pintype "passive")
			(teardrops
				(best_length_ratio 0.2)
				(max_length 1)
				(best_width_ratio 0.9)
				(max_width 2)
				(curved_edges yes)
				(filter_ratio 0.9)
				(enabled yes)
				(allow_two_segments yes)
				(prefer_zone_connections yes)
			)
		)
	)
	(footprint "antmicro-footprints:SOT-23-3"
		(layer "F.Cu")
		(at 304.975 138.76)
		(property "Reference" "Q1"
			(at 1.875 1.75 90)
			(layer "F.SilkS")
			(effects
				(font
					(size 0.7 0.7)
					(thickness 0.15)
				)
				(justify left bottom)
			)
		)
		(property "Value" "BSS138-7-F"
			(at -1.9 2.7 0)
			(layer "F.Fab")
			(effects
				(font
					(size 0.7 0.7)
					(thickness 0.15)
				)
				(justify left bottom)
			)
		)
		(property "Datasheet" "https://www.diodes.com/assets/Datasheets/ds30144.pdf"
			(at 0 0 0)
			(layer "F.Fab")
			(hide yes)
			(effects
				(font
					(size 1.27 1.27)
					(thickness 0.15)
				)
			)
		)
		(property "Author" "Antmicro"
			(at 0 0 0)
			(layer "F.Fab")
			(hide yes)
			(effects
				(font
					(size 1 1)
					(thickness 0.15)
				)
			)
		)
		(property "License" "Apache-2.0"
			(at 0 0 0)
			(layer "F.Fab")
			(hide yes)
			(effects
				(font
					(size 1 1)
					(thickness 0.15)
				)
			)
		)
		(property "MPN" "BSS138-7-F"
			(at 0 0 0)
			(layer "F.Fab")
			(hide yes)
			(effects
				(font
					(size 1 1)
					(thickness 0.15)
				)
			)
		)
		(property "Manufacturer" "Diodes Incorporated"
			(at 0 0 0)
			(layer "F.Fab")
			(hide yes)
			(effects
				(font
					(size 1 1)
					(thickness 0.15)
				)
			)
		)
		(sheetname "Power")
		(sheetfile "power.kicad_sch")
		(attr smd)
		(fp_line
			(start -1.45 -1.35)
			(end -0.85 -1.35)
			(stroke
				(width 0.15)
				(type solid)
			)
			(layer "F.SilkS")
		)
		(fp_line
			(start -0.85 -1.35)
			(end -0.7 -1.5)
			(stroke
				(width 0.15)
				(type solid)
			)
			(layer "F.SilkS")
		)
		(fp_line
			(start -0.7 1.5)
			(end -0.7 1.35)
			(stroke
				(width 0.15)
				(type solid)
			)
			(layer "F.SilkS")
		)
		(fp_line
			(start 0.7 -1.5)
			(end -0.7 -1.5)
			(stroke
				(width 0.15)
				(type solid)
			)
			(layer "F.SilkS")
		)
		(fp_line
			(start 0.7 -0.4)
			(end 0.7 -1.5)
			(stroke
				(width 0.15)
				(type solid)
			)
			(layer "F.SilkS")
		)
		(fp_line
			(start 0.7 0.4)
			(end 0.7 1.5)
			(stroke
				(width 0.15)
				(type solid)
			)
			(layer "F.SilkS")
		)
		(fp_line
			(start 0.7 1.5)
			(end -0.7 1.5)
			(stroke
				(width 0.15)
				(type solid)
			)
			(layer "F.SilkS")
		)
		(fp_line
			(start -1.75 -0.5)
			(end -1.75 -1.4)
			(stroke
				(width 0.05)
				(type solid)
			)
			(layer "F.CrtYd")
		)
		(fp_line
			(start -1.75 0.5)
			(end -0.85 0.5)
			(stroke
				(width 0.05)
				(type solid)
			)
			(layer "F.CrtYd")
		)
		(fp_line
			(start -1.75 1.4)
			(end -1.75 0.5)
			(stroke
				(width 0.05)
				(type solid)
			)
			(layer "F.CrtYd")
		)
		(fp_line
			(start -0.9 -1.6)
			(end -0.9 -1.4)
			(stroke
				(width 0.05)
				(type solid)
			)
			(layer "F.CrtYd")
		)
		(fp_line
			(start -0.9 -1.6)
			(end 0.825 -1.6)
			(stroke
				(width 0.05)
				(type solid)
			)
			(layer "F.CrtYd")
		)
		(fp_line
			(start -0.9 -1.4)
			(end -1.75 -1.4)
			(stroke
				(width 0.05)
				(type solid)
			)
			(layer "F.CrtYd")
		)
		(fp_line
			(start -0.85 -0.5)
			(end -1.75 -0.5)
			(stroke
				(width 0.05)
				(type solid)
			)
			(layer "F.CrtYd")
		)
		(fp_line
			(start -0.85 0.5)
			(end -0.85 -0.5)
			(stroke
				(width 0.05)
				(type solid)
			)
			(layer "F.CrtYd")
		)
		(fp_line
			(start -0.85 1.4)
			(end -1.75 1.4)
			(stroke
				(width 0.05)
				(type solid)
			)
			(layer "F.CrtYd")
		)
		(fp_line
			(start -0.85 1.65)
			(end -0.85 1.4)
			(stroke
				(width 0.05)
				(type solid)
			)
			(layer "F.CrtYd")
		)
		(fp_line
			(start 0.825 -1.6)
			(end 0.825 -0.45)
			(stroke
				(width 0.05)
				(type solid)
			)
			(layer "F.CrtYd")
		)
		(fp_line
			(start 0.825 -0.45)
			(end 1.75 -0.45)
			(stroke
				(width 0.05)
				(type solid)
			)
			(layer "F.CrtYd")
		)
		(fp_line
			(start 0.85 0.45)
			(end 0.85 1.65)
			(stroke
				(width 0.05)
				(type solid)
			)
			(layer "F.CrtYd")
		)
		(fp_line
			(start 0.85 1.65)
			(end -0.85 1.65)
			(stroke
				(width 0.05)
				(type solid)
			)
			(layer "F.CrtYd")
		)
		(fp_line
			(start 1.75 -0.45)
			(end 1.75 0.45)
			(stroke
				(width 0.05)
				(type solid)
			)
			(layer "F.CrtYd")
		)
		(fp_line
			(start 1.75 0.45)
			(end 0.85 0.45)
			(stroke
				(width 0.05)
				(type solid)
			)
			(layer "F.CrtYd")
		)
		(fp_line
			(start -0.712 -1.325)
			(end -0.712 1.523)
			(stroke
				(width 0.15)
				(type solid)
			)
			(layer "F.Fab")
		)
		(fp_line
			(start -0.712 1.519)
			(end 0.688 1.519)
			(stroke
				(width 0.15)
				(type solid)
			)
			(layer "F.Fab")
		)
		(fp_line
			(start -0.437 -1.526)
			(end -0.712 -1.325)
			(stroke
				(width 0.15)
				(type solid)
			)
			(layer "F.Fab")
		)
		(fp_line
			(start -0.437 -1.526)
			(end 0.688 -1.526)
			(stroke
				(width 0.15)
				(type solid)
			)
			(layer "F.Fab")
		)
		(fp_line
			(start 0.688 1.519)
			(end 0.688 -1.52)
			(stroke
				(width 0.15)
				(type solid)
			)
			(layer "F.Fab")
		)
		(pad "1" smd roundrect
			(at -1.1 -0.951)
			(size 1 0.6)
			(layers "F.Cu" "F.Mask" "F.Paste")
			(roundrect_rratio 0.15)
			(net 533 "/Com Express 7 MGMT/PSON")
			(pinfunction "G")
			(pintype "bidirectional")
			(teardrops
				(best_length_ratio 0.2)
				(max_length 1)
				(best_width_ratio 0.9)
				(max_width 2)
				(curved_edges yes)
				(filter_ratio 0.9)
				(enabled yes)
				(allow_two_segments yes)
				(prefer_zone_connections yes)
			)
		)
		(pad "2" smd roundrect
			(at -1.1 0.949)
			(size 1 0.6)
			(layers "F.Cu" "F.Mask" "F.Paste")
			(roundrect_rratio 0.15)
			(net 1 "GND")
			(pinfunction "S")
			(pintype "bidirectional")
			(teardrops
				(best_length_ratio 0.2)
				(max_length 1)
				(best_width_ratio 0.9)
				(max_width 2)
				(curved_edges yes)
				(filter_ratio 0.9)
				(enabled yes)
				(allow_two_segments yes)
				(prefer_zone_connections yes)
			)
		)
		(pad "3" smd roundrect
			(at 1.1 -0.0005)
			(size 1 0.6)
			(layers "F.Cu" "F.Mask" "F.Paste")
			(roundrect_rratio 0.15)
			(net 534 "Net-(Q1-D)")
			(pinfunction "D")
			(pintype "bidirectional")
			(teardrops
				(best_length_ratio 0.2)
				(max_length 1)
				(best_width_ratio 0.9)
				(max_width 2)
				(curved_edges yes)
				(filter_ratio 0.9)
				(enabled yes)
				(allow_two_segments yes)
				(prefer_zone_connections yes)
			)
		)
	)
	(footprint "antmicro-footprints:TSSOP-8_3x3mm_P0.65mm"
		(layer "F.Cu")
		(at 142.877 149.258 -90)
		(property "Reference" "U42"
			(at -1.248 1.827 90)
			(layer "F.SilkS")
			(effects
				(font
					(size 0.7 0.7)
					(thickness 0.15)
				)
				(justify right bottom)
			)
		)
		(property "Value" "NTS0102_TSSOP"
			(at 0 2.8 90)
			(layer "F.Fab")
			(effects
				(font
					(size 0.7 0.7)
					(thickness 0.15)
				)
				(justify right bottom)
			)
		)
		(property "Datasheet" "https://www.mouser.com/datasheet/2/302/NTS0102-1127324.pdf"
			(at 0 0 270)
			(layer "F.Fab")
			(hide yes)
			(effects
				(font
					(size 1.27 1.27)
					(thickness 0.15)
				)
			)
		)
		(property "Author" "Antmicro"
			(at -6.381 292.135 0)
			(layer "F.Fab")
			(hide yes)
			(effects
				(font
					(size 1 1)
					(thickness 0.15)
				)
			)
		)
		(property "License" "Apache-2.0"
			(at -6.381 292.135 0)
			(layer "F.Fab")
			(hide yes)
			(effects
				(font
					(size 1 1)
					(thickness 0.15)
				)
			)
		)
		(property "MPN" "NTS0102DP"
			(at -6.381 292.135 0)
			(layer "F.Fab")
			(hide yes)
			(effects
				(font
					(size 1 1)
					(thickness 0.15)
				)
			)
		)
		(property "Manufacturer" "NXP"
			(at -6.381 292.135 0)
			(layer "F.Fab")
			(hide yes)
			(effects
				(font
					(size 1 1)
					(thickness 0.15)
				)
			)
		)
		(sheetname "KR to SFI #1")
		(sheetfile "kr_sfi.kicad_sch")
		(attr smd)
		(fp_line
			(start -1.55 1.561)
			(end 1.552 1.561)
			(stroke
				(width 0.15)
				(type solid)
			)
			(layer "F.SilkS")
		)
		(fp_line
			(start -1.525 -1.537)
			(end 1.552 -1.539)
			(stroke
				(width 0.15)
				(type solid)
			)
			(layer "F.SilkS")
		)
		(fp_circle
			(center -1.87 -1.4)
			(end -1.82 -1.4)
			(stroke
				(width 0.15)
				(type solid)
			)
			(fill yes)
			(layer "F.SilkS")
		)
		(fp_rect
			(start -3.15 -1.789)
			(end 3.15 1.811)
			(stroke
				(width 0.05)
				(type solid)
			)
			(fill no)
			(layer "F.CrtYd")
		)
		(fp_line
			(start -1.55 1.561)
			(end 1.552 1.561)
			(stroke
				(width 0.15)
				(type solid)
			)
			(layer "F.Fab")
		)
		(fp_line
			(start -1.55 -0.937)
			(end -1.55 1.561)
			(stroke
				(width 0.15)
				(type solid)
			)
			(layer "F.Fab")
		)
		(fp_line
			(start -1.55 -0.937)
			(end -0.949 -1.539)
			(stroke
				(width 0.15)
				(type solid)
			)
			(layer "F.Fab")
		)
		(fp_line
			(start -0.949 -1.539)
			(end 1.552 -1.539)
			(stroke
				(width 0.15)
				(type solid)
			)
			(layer "F.Fab")
		)
		(fp_line
			(start 1.552 -1.539)
			(end 1.552 1.561)
			(stroke
				(width 0.15)
				(type solid)
			)
			(layer "F.Fab")
		)
		(pad "1" smd roundrect
			(at -2.148 -0.962 270)
			(size 1.47 0.4)
			(layers "F.Cu" "F.Mask" "F.Paste")
			(roundrect_rratio 0.25)
			(net 430 "/2xSFP+/MDIO0.MDC")
			(pinfunction "B_{2}")
			(pintype "bidirectional")
			(teardrops
				(best_length_ratio 0.2)
				(max_length 1)
				(best_width_ratio 0.9)
				(max_width 2)
				(curved_edges yes)
				(filter_ratio 0.9)
				(enabled yes)
				(allow_two_segments yes)
				(prefer_zone_connections yes)
			)
		)
		(pad "2" smd roundrect
			(at -2.148 -0.313 270)
			(size 1.47 0.4)
			(layers "F.Cu" "F.Mask" "F.Paste")
			(roundrect_rratio 0.25)
			(net 1 "GND")
			(pinfunction "GND")
			(pintype "power_in")
			(teardrops
				(best_length_ratio 0.2)
				(max_length 1)
				(best_width_ratio 0.9)
				(max_width 2)
				(curved_edges yes)
				(filter_ratio 0.9)
				(enabled yes)
				(allow_two_segments yes)
				(prefer_zone_connections yes)
			)
		)
		(pad "3" smd roundrect
			(at -2.148 0.338 270)
			(size 1.47 0.4)
			(layers "F.Cu" "F.Mask" "F.Paste")
			(roundrect_rratio 0.25)
			(net 78 "+1V8")
			(pinfunction "VCC_{A}")
			(pintype "power_in")
			(teardrops
				(best_length_ratio 0.2)
				(max_length 1)
				(best_width_ratio 0.9)
				(max_width 2)
				(curved_edges yes)
				(filter_ratio 0.9)
				(enabled yes)
				(allow_two_segments yes)
				(prefer_zone_connections yes)
			)
		)
		(pad "4" smd roundrect
			(at -2.148 0.987 270)
			(size 1.47 0.4)
			(layers "F.Cu" "F.Mask" "F.Paste")
			(roundrect_rratio 0.25)
			(net 650 "/2xSFP+/KR to SFI #1/MDC_R")
			(pinfunction "A_{2}")
			(pintype "bidirectional")
			(teardrops
				(best_length_ratio 0.2)
				(max_length 1)
				(best_width_ratio 0.9)
				(max_width 2)
				(curved_edges yes)
				(filter_ratio 0.9)
				(enabled yes)
				(allow_two_segments yes)
				(prefer_zone_connections yes)
			)
		)
		(pad "5" smd roundrect
			(at 2.151 0.987 270)
			(size 1.47 0.4)
			(layers "F.Cu" "F.Mask" "F.Paste")
			(roundrect_rratio 0.25)
			(net 648 "/2xSFP+/KR to SFI #1/MDIO_R")
			(pinfunction "A_{1}")
			(pintype "bidirectional")
			(teardrops
				(best_length_ratio 0.2)
				(max_length 1)
				(best_width_ratio 0.9)
				(max_width 2)
				(curved_edges yes)
				(filter_ratio 0.9)
				(enabled yes)
				(allow_two_segments yes)
				(prefer_zone_connections yes)
			)
		)
		(pad "6" smd roundrect
			(at 2.151 0.338 270)
			(size 1.47 0.4)
			(layers "F.Cu" "F.Mask" "F.Paste")
			(roundrect_rratio 0.25)
			(net 78 "+1V8")
			(pinfunction "OE")
			(pintype "input")
			(teardrops
				(best_length_ratio 0.2)
				(max_length 1)
				(best_width_ratio 0.9)
				(max_width 2)
				(curved_edges yes)
				(filter_ratio 0.9)
				(enabled yes)
				(allow_two_segments yes)
				(prefer_zone_connections yes)
			)
		)
		(pad "7" smd roundrect
			(at 2.151 -0.313 270)
			(size 1.47 0.4)
			(layers "F.Cu" "F.Mask" "F.Paste")
			(roundrect_rratio 0.25)
			(net 2 "+3V3")
			(pinfunction "VCC_{B}")
			(pintype "power_in")
			(teardrops
				(best_length_ratio 0.2)
				(max_length 1)
				(best_width_ratio 0.9)
				(max_width 2)
				(curved_edges yes)
				(filter_ratio 0.9)
				(enabled yes)
				(allow_two_segments yes)
				(prefer_zone_connections yes)
			)
		)
		(pad "8" smd roundrect
			(at 2.151 -0.962 270)
			(size 1.47 0.4)
			(layers "F.Cu" "F.Mask" "F.Paste")
			(roundrect_rratio 0.25)
			(net 491 "/2xSFP+/MDIO0.MDIO")
			(pinfunction "B_{1}")
			(pintype "bidirectional")
			(teardrops
				(best_length_ratio 0.2)
				(max_length 1)
				(best_width_ratio 0.9)
				(max_width 2)
				(curved_edges yes)
				(filter_ratio 0.9)
				(enabled yes)
				(allow_two_segments yes)
				(prefer_zone_connections yes)
			)
		)
	)
)
